FILE_TYPE = CONNECTIVITY;
{Allegro Design Entry HDL 17.4-2019 S026 (4007227) 1/17/2022}
"PAGE_NUMBER" = 212;
0"NC";
1"GND\g";
2"GND\g";
3"GND\g";
4"GND\g";
5"GND\g";
6"GND\g";
7"GND\g";
8"GND\g";
9"GND\g";
10"GND\g";
11"GND\g";
12"GND\g";
13"GND\g";
14"GND\g";
15"GND\g";
16"GND\g";
17"GND\g";
18"GND\g";
19"GND\g";
20"GND\g";
21"GND\g";
22"GND\g";
23"GND\g";
24"GND\g";
25"GND\g";
26"GND\g";
27"GND\g";
28"GND\g";
29"GND\g";
30"GND\g";
31"GND\g";
32"GND\g";
33"GND\g";
34"GND\g";
35"GND\g";
36"GND\g";
37"GND\g";
38"GND\g";
39"GND\g";
40"GND\g";
41"GND\g";
42"GND\g";
43"GND\g";
44"GND\g";
45"GND\g";
46"GND\g";
47"GND\g";
48"GND\g";
49"GND\g";
50"GND\g";
51"GND\g";
52"GND\g";
53"GND\g";
54"GND\g";
55"GND\g";
%"HOLE"
"1","(-8725,4225)","0","pure_quanta","I10";
;
LOCATION"H76"
$SEC"1"
CDS_SEC"1"
MATERIAL"EMPTY"
PACK_TYPE"TH"
NEEDS_NO_SIZE"TRUE"
CDS_LIB"pure_quanta"
PART_NUMBER"HOLE1187";
"1 \B"
$PN"1"53;
%"CONN1_10165288101LF"
"1","(-1650,5400)","0","pure_quanta","I101";
;
LOCATION"J122"
$SEC"1"
CDS_SEC"1"
VALUE"CONN1_10165288-101LF"
PART_TYPE"THLF"
MATERIAL"IO"
CDS_LIB"pure_quanta"
NEEDS_NO_SIZE"TRUE"
CDS_LMAN_SYM_OUTLINE"-50,125,50,-125"
PART_NUMBER"DFHS03FR030";
"NC1"
$PN"SCR_H1"0;
%"CONN1_10165288101LF"
"1","(-825,5400)","0","pure_quanta","I106";
;
LOCATION"J123"
$SEC"1"
CDS_SEC"1"
MATERIAL"IO"
VALUE"CONN1_10165288-101LF"
PART_TYPE"THLF"
NEEDS_NO_SIZE"TRUE"
CDS_LMAN_SYM_OUTLINE"-50,125,50,-125"
CDS_LIB"pure_quanta"
PART_NUMBER"DFHS03FR030";
"NC1"
$PN"SCR_H1"0;
%"UNIVERSAL_GND"
"1","(-8450,4075)","0","pure_quanta_power","I11";
;
CDS_LIB"pure_quanta_power"
HDL_POWER"GND";
"A"47;
%"HOLE"
"1","(-2875,475)","0","pure_quanta","I111";
;
LOCATION"H126"
$SEC"1"
CDS_SEC"1"
MATERIAL"EMPTY"
PACK_TYPE"TH"
CDS_LIB"pure_quanta"
NEEDS_NO_SIZE"TRUE"
PART_NUMBER"TMP-C_T2I_ALEX_1121_1";
"1 \B"
$PN"1"0;
%"HOLE"
"1","(-825,1400)","0","pure_quanta","I113";
;
LOCATION"H6000"
$SEC"1"
CDS_SEC"1"
PACK_TYPE"TH"
MATERIAL"EMPTY"
CDS_LIB"pure_quanta"
NEEDS_NO_SIZE"TRUE"
PART_NUMBER"HOLE1226";
"1 \B"
$PN"1"1;
%"UNIVERSAL_GND"
"1","(-1025,1325)","0","pure_quanta_power","I114";
;
CDS_LIB"pure_quanta_power"
HDL_POWER"GND";
"A"1;
%"UNIVERSAL_GND"
"1","(-500,1300)","0","pure_quanta_power","I115";
;
CDS_LIB"pure_quanta_power"
HDL_POWER"GND";
"A"2;
%"HOLE"
"1","(-300,1375)","0","pure_quanta","I116";
;
LOCATION"H6001"
$SEC"1"
CDS_SEC"1"
MATERIAL"EMPTY"
PACK_TYPE"TH"
NEEDS_NO_SIZE"TRUE"
CDS_LIB"pure_quanta"
PART_NUMBER"HOLE1226";
"1 \B"
$PN"1"2;
%"HOLE"
"1","(-8175,4225)","0","pure_quanta","I12";
;
LOCATION"H77"
$SEC"1"
CDS_SEC"1"
MATERIAL"EMPTY"
PACK_TYPE"TH"
NEEDS_NO_SIZE"TRUE"
CDS_LIB"pure_quanta"
PART_NUMBER"HOLE1187";
"1 \B"
$PN"1"47;
%"GND_HOLE"
"1","(-7225,800)","0","pure_quanta","I120";
;
LOCATION"H111"
SEC"1"
PACK_TYPE"TH"
MATERIAL"EMPTY"
SEC_TYPE"TH"
CDS_LIB"pure_quanta"
NEEDS_NO_SIZE"TRUE"
PART_NUMBER"TMP-QGND_HOLE12";
"GND5"
$PN"5"48;
"GND6"
$PN"6"48;
"GND2"
$PN"2"48;
"GND3"
$PN"3"48;
"GND7"
$PN"7"48;
"GND8"
$PN"8"48;
"GND9"
$PN"9"48;
"GND4"
$PN"4"48;
%"UNIVERSAL_GND"
"1","(-7500,400)","0","pure_quanta_power","I122";
;
CDS_LIB"pure_quanta_power"
HDL_POWER"GND";
"A"48;
%"GND_HOLE"
"1","(-6475,825)","0","pure_quanta","I123";
;
LOCATION"H112"
SEC"1"
MATERIAL"EMPTY"
PACK_TYPE"TH"
SEC_TYPE"TH"
CDS_LIB"pure_quanta"
NEEDS_NO_SIZE"TRUE"
PART_NUMBER"TMP-QGND_HOLE12";
"GND5"
$PN"5"49;
"GND6"
$PN"6"49;
"GND2"
$PN"2"49;
"GND3"
$PN"3"49;
"GND7"
$PN"7"49;
"GND8"
$PN"8"49;
"GND9"
$PN"9"49;
"GND4"
$PN"4"49;
%"UNIVERSAL_GND"
"1","(-6750,425)","0","pure_quanta_power","I124";
;
CDS_LIB"pure_quanta_power"
HDL_POWER"GND";
"A"49;
%"HOLE"
"1","(-8800,5875)","0","pure_quanta","I125";
;
LOCATION"H86"
$SEC"1"
CDS_SEC"1"
PACK_TYPE"TH"
MATERIAL"EMPTY"
CDS_LIB"pure_quanta"
NEEDS_NO_SIZE"TRUE"
PART_NUMBER"HOLE596";
"1 \B"
$PN"1"3;
%"UNIVERSAL_GND"
"1","(-9100,5750)","0","pure_quanta_power","I126";
;
CDS_LIB"pure_quanta_power"
HDL_POWER"GND";
"A"3;
%"HOLE"
"1","(-8775,5325)","0","pure_quanta","I127";
;
LOCATION"H87"
$SEC"1"
CDS_SEC"1"
PACK_TYPE"TH"
MATERIAL"EMPTY"
CDS_LIB"pure_quanta"
NEEDS_NO_SIZE"TRUE"
PART_NUMBER"HOLE596";
"1 \B"
$PN"1"4;
%"UNIVERSAL_GND"
"1","(-9050,5225)","0","pure_quanta_power","I128";
;
CDS_LIB"pure_quanta_power"
HDL_POWER"GND";
"A"4;
%"HOLE"
"1","(-8175,5900)","0","pure_quanta","I129";
;
LOCATION"H88"
$SEC"1"
CDS_SEC"1"
MATERIAL"EMPTY"
PACK_TYPE"TH"
NEEDS_NO_SIZE"TRUE"
CDS_LIB"pure_quanta"
PART_NUMBER"HOLE596";
"1 \B"
$PN"1"5;
%"UNIVERSAL_GND"
"1","(-8475,5800)","0","pure_quanta_power","I130";
;
CDS_LIB"pure_quanta_power"
HDL_POWER"GND";
"A"5;
%"UNIVERSAL_GND"
"1","(-8425,5225)","0","pure_quanta_power","I131";
;
CDS_LIB"pure_quanta_power"
HDL_POWER"GND";
"A"6;
%"HOLE"
"1","(-8150,5325)","0","pure_quanta","I132";
;
LOCATION"H89"
$SEC"1"
CDS_SEC"1"
MATERIAL"EMPTY"
PACK_TYPE"TH"
NEEDS_NO_SIZE"TRUE"
CDS_LIB"pure_quanta"
PART_NUMBER"HOLE596";
"1 \B"
$PN"1"6;
%"HOLE"
"1","(-7475,5900)","0","pure_quanta","I133";
;
LOCATION"H91"
$SEC"1"
CDS_SEC"1"
PACK_TYPE"TH"
MATERIAL"EMPTY"
NEEDS_NO_SIZE"TRUE"
CDS_LIB"pure_quanta"
PART_NUMBER"HOLE596";
"1 \B"
$PN"1"7;
%"UNIVERSAL_GND"
"1","(-7775,5825)","0","pure_quanta_power","I134";
;
CDS_LIB"pure_quanta_power"
HDL_POWER"GND";
"A"7;
%"HOLE"
"1","(-7475,5350)","0","pure_quanta","I135";
;
LOCATION"H92"
$SEC"1"
CDS_SEC"1"
MATERIAL"EMPTY"
PACK_TYPE"TH"
CDS_LIB"pure_quanta"
NEEDS_NO_SIZE"TRUE"
PART_NUMBER"HOLE596";
"1 \B"
$PN"1"8;
%"UNIVERSAL_GND"
"1","(-7750,5250)","0","pure_quanta_power","I136";
;
CDS_LIB"pure_quanta_power"
HDL_POWER"GND";
"A"8;
%"UNIVERSAL_GND"
"1","(-7125,5850)","0","pure_quanta_power","I137";
;
CDS_LIB"pure_quanta_power"
HDL_POWER"GND";
"A"9;
%"HOLE"
"1","(-6850,5900)","0","pure_quanta","I138";
;
LOCATION"H93"
$SEC"1"
CDS_SEC"1"
MATERIAL"EMPTY"
PACK_TYPE"TH"
CDS_LIB"pure_quanta"
NEEDS_NO_SIZE"TRUE"
PART_NUMBER"HOLE596";
"1 \B"
$PN"1"9;
%"UNIVERSAL_GND"
"1","(-7050,5250)","0","pure_quanta_power","I139";
;
CDS_LIB"pure_quanta_power"
HDL_POWER"GND";
"A"10;
%"HOLE"
"1","(-6800,5325)","0","pure_quanta","I140";
;
LOCATION"H94"
$SEC"1"
CDS_SEC"1"
MATERIAL"EMPTY"
PACK_TYPE"TH"
CDS_LIB"pure_quanta"
NEEDS_NO_SIZE"TRUE"
PART_NUMBER"HOLE596";
"1 \B"
$PN"1"10;
%"HOLE"
"1","(-6200,5875)","0","pure_quanta","I141";
;
LOCATION"H95"
$SEC"1"
CDS_SEC"1"
PACK_TYPE"TH"
MATERIAL"EMPTY"
CDS_LIB"pure_quanta"
NEEDS_NO_SIZE"TRUE"
PART_NUMBER"HOLE596";
"1 \B"
$PN"1"12;
%"HOLE"
"1","(-6150,5350)","0","pure_quanta","I142";
;
LOCATION"H96"
$SEC"1"
CDS_SEC"1"
MATERIAL"EMPTY"
PACK_TYPE"TH"
CDS_LIB"pure_quanta"
NEEDS_NO_SIZE"TRUE"
PART_NUMBER"HOLE596";
"1 \B"
$PN"1"11;
%"UNIVERSAL_GND"
"1","(-6400,5300)","0","pure_quanta_power","I143";
;
CDS_LIB"pure_quanta_power"
HDL_POWER"GND";
"A"11;
%"UNIVERSAL_GND"
"1","(-6450,5825)","0","pure_quanta_power","I144";
;
CDS_LIB"pure_quanta_power"
HDL_POWER"GND";
"A"12;
%"HOLE"
"1","(-5475,5925)","0","pure_quanta","I145";
;
LOCATION"H97"
$SEC"1"
CDS_SEC"1"
PACK_TYPE"TH"
MATERIAL"EMPTY"
CDS_LIB"pure_quanta"
NEEDS_NO_SIZE"TRUE"
PART_NUMBER"HOLE596";
"1 \B"
$PN"1"13;
%"UNIVERSAL_GND"
"1","(-5725,5850)","0","pure_quanta_power","I146";
;
CDS_LIB"pure_quanta_power"
HDL_POWER"GND";
"A"13;
%"HOLE"
"1","(-5450,5300)","0","pure_quanta","I147";
;
LOCATION"H98"
$SEC"1"
CDS_SEC"1"
MATERIAL"EMPTY"
PACK_TYPE"TH"
NEEDS_NO_SIZE"TRUE"
CDS_LIB"pure_quanta"
PART_NUMBER"HOLE596";
"1 \B"
$PN"1"14;
%"UNIVERSAL_GND"
"1","(-5700,5200)","0","pure_quanta_power","I148";
;
CDS_LIB"pure_quanta_power"
HDL_POWER"GND";
"A"14;
%"HOLE"
"1","(-4750,5925)","0","pure_quanta","I149";
;
LOCATION"H99"
$SEC"1"
CDS_SEC"1"
MATERIAL"EMPTY"
PACK_TYPE"TH"
NEEDS_NO_SIZE"TRUE"
CDS_LIB"pure_quanta"
PART_NUMBER"HOLE596";
"1 \B"
$PN"1"15;
%"UNIVERSAL_GND"
"1","(-5025,5850)","0","pure_quanta_power","I150";
;
CDS_LIB"pure_quanta_power"
HDL_POWER"GND";
"A"15;
%"UNIVERSAL_GND"
"1","(-5000,5200)","0","pure_quanta_power","I151";
;
CDS_LIB"pure_quanta_power"
HDL_POWER"GND";
"A"16;
%"HOLE"
"1","(-4725,5300)","0","pure_quanta","I152";
;
LOCATION"H100"
$SEC"1"
CDS_SEC"1"
PACK_TYPE"TH"
MATERIAL"EMPTY"
CDS_LIB"pure_quanta"
NEEDS_NO_SIZE"TRUE"
PART_NUMBER"HOLE596";
"1 \B"
$PN"1"16;
%"HOLE"
"1","(-4100,5925)","0","pure_quanta","I153";
;
LOCATION"H101"
$SEC"1"
CDS_SEC"1"
PACK_TYPE"TH"
MATERIAL"EMPTY"
CDS_LIB"pure_quanta"
NEEDS_NO_SIZE"TRUE"
PART_NUMBER"HOLE596";
"1 \B"
$PN"1"17;
%"UNIVERSAL_GND"
"1","(-4350,5850)","0","pure_quanta_power","I154";
;
CDS_LIB"pure_quanta_power"
HDL_POWER"GND";
"A"17;
%"UNIVERSAL_GND"
"1","(-4350,5225)","0","pure_quanta_power","I155";
;
CDS_LIB"pure_quanta_power"
HDL_POWER"GND";
"A"18;
%"HOLE"
"1","(-4075,5300)","0","pure_quanta","I156";
;
LOCATION"H102"
$SEC"1"
CDS_SEC"1"
MATERIAL"EMPTY"
PACK_TYPE"TH"
CDS_LIB"pure_quanta"
NEEDS_NO_SIZE"TRUE"
PART_NUMBER"HOLE596";
"1 \B"
$PN"1"18;
%"HOLE"
"1","(-3325,5950)","0","pure_quanta","I157";
;
LOCATION"H103"
$SEC"1"
CDS_SEC"1"
MATERIAL"EMPTY"
PACK_TYPE"TH"
NEEDS_NO_SIZE"TRUE"
CDS_LIB"pure_quanta"
PART_NUMBER"HOLE596";
"1 \B"
$PN"1"19;
%"UNIVERSAL_GND"
"1","(-3575,5875)","0","pure_quanta_power","I158";
;
CDS_LIB"pure_quanta_power"
HDL_POWER"GND";
"A"19;
%"HOLE"
"1","(-3325,5325)","0","pure_quanta","I159";
;
LOCATION"H104"
$SEC"1"
CDS_SEC"1"
PACK_TYPE"TH"
MATERIAL"EMPTY"
NEEDS_NO_SIZE"TRUE"
CDS_LIB"pure_quanta"
PART_NUMBER"HOLE596";
"1 \B"
$PN"1"20;
%"UNIVERSAL_GND"
"1","(-3600,5250)","0","pure_quanta_power","I160";
;
CDS_LIB"pure_quanta_power"
HDL_POWER"GND";
"A"20;
%"HOLE"
"1","(-2675,5950)","0","pure_quanta","I161";
;
LOCATION"H105"
$SEC"1"
CDS_SEC"1"
MATERIAL"EMPTY"
PACK_TYPE"TH"
CDS_LIB"pure_quanta"
NEEDS_NO_SIZE"TRUE"
PART_NUMBER"HOLE596";
"1 \B"
$PN"1"21;
%"UNIVERSAL_GND"
"1","(-2925,5875)","0","pure_quanta_power","I162";
;
CDS_LIB"pure_quanta_power"
HDL_POWER"GND";
"A"21;
%"HOLE"
"1","(-2675,5300)","0","pure_quanta","I163";
;
LOCATION"H106"
$SEC"1"
CDS_SEC"1"
MATERIAL"EMPTY"
PACK_TYPE"TH"
NEEDS_NO_SIZE"TRUE"
CDS_LIB"pure_quanta"
PART_NUMBER"HOLE596";
"1 \B"
$PN"1"22;
%"UNIVERSAL_GND"
"1","(-2925,5225)","0","pure_quanta_power","I164";
;
CDS_LIB"pure_quanta_power"
HDL_POWER"GND";
"A"22;
%"UNIVERSAL_GND"
"1","(-2250,5925)","0","pure_quanta_power","I165";
;
CDS_LIB"pure_quanta_power"
HDL_POWER"GND";
"A"23;
%"HOLE"
"1","(-2000,6000)","0","pure_quanta","I166";
;
LOCATION"H128"
$SEC"1"
CDS_SEC"1"
MATERIAL"EMPTY"
PACK_TYPE"TH"
NEEDS_NO_SIZE"TRUE"
CDS_LIB"pure_quanta"
PART_NUMBER"HOLE596";
"1 \B"
$PN"1"23;
%"HOLE"
"1","(-825,6025)","0","pure_quanta","I167";
;
LOCATION"H90"
$SEC"1"
CDS_SEC"1"
MATERIAL"EMPTY"
PACK_TYPE"TH"
CDS_LIB"pure_quanta"
NEEDS_NO_SIZE"TRUE"
PART_NUMBER"HOLE372";
"1 \B"
$PN"1"0;
%"HOLE"
"1","(-525,3975)","0","pure_quanta","I168";
;
LOCATION"H6002"
$SEC"1"
CDS_SEC"1"
MATERIAL"EMPTY"
PACK_TYPE"TH"
NEEDS_NO_SIZE"TRUE"
CDS_LIB"pure_quanta"
PART_NUMBER"HOLE1195";
"1 \B"
$PN"1"24;
%"UNIVERSAL_GND"
"1","(-850,3800)","0","pure_quanta_power","I169";
;
CDS_LIB"pure_quanta_power"
HDL_POWER"GND";
"A"24;
%"HOLE"
"1","(-8775,2175)","0","pure_quanta","I170";
;
LOCATION"H2"
$SEC"1"
CDS_SEC"1"
MATERIAL"EMPTY"
PACK_TYPE"TH"
CDS_LIB"pure_quanta"
NEEDS_NO_SIZE"TRUE"
PART_NUMBER"HOLE1226";
"1 \B"
$PN"1"25;
%"UNIVERSAL_GND"
"1","(-8975,2100)","0","pure_quanta_power","I171";
;
CDS_LIB"pure_quanta_power"
HDL_POWER"GND";
"A"25;
%"HOLE"
"1","(-8175,2125)","0","pure_quanta","I176";
;
LOCATION"H8"
$SEC"1"
CDS_SEC"1"
PACK_TYPE"TH"
MATERIAL"EMPTY"
NEEDS_NO_SIZE"TRUE"
CDS_LIB"pure_quanta"
PART_NUMBER"HOLE1226";
"1 \B"
$PN"1"26;
%"UNIVERSAL_GND"
"1","(-8375,2050)","0","pure_quanta_power","I177";
;
CDS_LIB"pure_quanta_power"
HDL_POWER"GND";
"A"26;
%"HOLE"
"1","(-7675,2100)","0","pure_quanta","I178";
;
LOCATION"H10"
$SEC"1"
CDS_SEC"1"
PACK_TYPE"TH"
MATERIAL"EMPTY"
NEEDS_NO_SIZE"TRUE"
CDS_LIB"pure_quanta"
PART_NUMBER"HOLE1226";
"1 \B"
$PN"1"27;
%"UNIVERSAL_GND"
"1","(-7875,2025)","0","pure_quanta_power","I179";
;
CDS_LIB"pure_quanta_power"
HDL_POWER"GND";
"A"27;
%"UNIVERSAL_GND"
"1","(-6225,2050)","0","pure_quanta_power","I186";
;
CDS_LIB"pure_quanta_power"
HDL_POWER"GND";
"A"28;
%"HOLE"
"1","(-6025,2125)","0","pure_quanta","I187";
;
LOCATION"H12"
$SEC"1"
CDS_SEC"1"
MATERIAL"EMPTY"
PACK_TYPE"TH"
CDS_LIB"pure_quanta"
NEEDS_NO_SIZE"TRUE"
PART_NUMBER"HOLE1226";
"1 \B"
$PN"1"28;
%"UNIVERSAL_GND"
"1","(-6775,2050)","0","pure_quanta_power","I192";
;
CDS_LIB"pure_quanta_power"
HDL_POWER"GND";
"A"29;
%"HOLE"
"1","(-6575,2125)","0","pure_quanta","I193";
;
LOCATION"H5"
$SEC"1"
CDS_SEC"1"
MATERIAL"EMPTY"
PACK_TYPE"TH"
NEEDS_NO_SIZE"TRUE"
CDS_LIB"pure_quanta"
PART_NUMBER"HOLE1226";
"1 \B"
$PN"1"29;
%"UNIVERSAL_GND"
"1","(-7325,2050)","0","pure_quanta_power","I194";
;
CDS_LIB"pure_quanta_power"
HDL_POWER"GND";
"A"30;
%"HOLE"
"1","(-7125,2125)","0","pure_quanta","I195";
;
LOCATION"H3"
$SEC"1"
CDS_SEC"1"
MATERIAL"EMPTY"
PACK_TYPE"TH"
NEEDS_NO_SIZE"TRUE"
CDS_LIB"pure_quanta"
PART_NUMBER"HOLE1226";
"1 \B"
$PN"1"30;
%"UNIVERSAL_GND"
"1","(-8450,2725)","0","pure_quanta_power","I21";
;
CDS_LIB"pure_quanta_power"
HDL_POWER"GND";
"A"31;
%"UNIVERSAL_GND"
"1","(-9125,450)","0","pure_quanta_power","I24";
;
CDS_LIB"pure_quanta_power"
HDL_POWER"GND";
"A"50;
%"GND_HOLE"
"1","(-8850,850)","0","pure_quanta","I25";
;
LOCATION"H113"
$SEC"1"
CDS_SEC"1"
PACK_TYPE"TH"
MATERIAL"EMPTY"
NEEDS_NO_SIZE"TRUE"
CDS_LIB"pure_quanta"
PART_NUMBER"GND_HOLE140";
"GND5"
$PN"5"50;
"GND6"
$PN"6"50;
"GND2"
$PN"2"50;
"GND3"
$PN"3"50;
"GND7"
$PN"7"50;
"GND8"
$PN"8"50;
"GND9"
$PN"9"50;
"GND4"
$PN"4"50;
%"HOLE"
"1","(-8250,2800)","0","pure_quanta","I26";
;
LOCATION"H22"
$SEC"1"
CDS_SEC"1"
PACK_TYPE"TH"
MATERIAL"EMPTY"
CDS_LIB"pure_quanta"
NEEDS_NO_SIZE"TRUE"
PART_NUMBER"HOLE1226";
"1 \B"
$PN"1"31;
%"HOLE"
"1","(-7700,2800)","0","pure_quanta","I27";
;
LOCATION"H8028"
$SEC"1"
CDS_SEC"1"
PACK_TYPE"TH"
MATERIAL"EMPTY"
NEEDS_NO_SIZE"TRUE"
CDS_LIB"pure_quanta"
PART_NUMBER"HOLE1226";
"1 \B"
$PN"1"32;
%"UNIVERSAL_GND"
"1","(-7900,2725)","0","pure_quanta_power","I28";
;
CDS_LIB"pure_quanta_power"
HDL_POWER"GND";
"A"32;
%"UNIVERSAL_GND"
"1","(-8350,475)","0","pure_quanta_power","I29";
;
CDS_LIB"pure_quanta_power"
HDL_POWER"GND";
"A"51;
%"UNIVERSAL_GND"
"1","(-9075,2750)","0","pure_quanta_power","I3";
;
CDS_LIB"pure_quanta_power"
HDL_POWER"GND";
"A"33;
%"GND_HOLE"
"1","(-8075,875)","0","pure_quanta","I30";
;
LOCATION"H114"
$SEC"1"
CDS_SEC"1"
MATERIAL"EMPTY"
PACK_TYPE"TH"
NEEDS_NO_SIZE"TRUE"
CDS_LIB"pure_quanta"
PART_NUMBER"GND_HOLE140";
"GND5"
$PN"5"51;
"GND6"
$PN"6"51;
"GND2"
$PN"2"51;
"GND3"
$PN"3"51;
"GND7"
$PN"7"51;
"GND8"
$PN"8"51;
"GND9"
$PN"9"51;
"GND4"
$PN"4"51;
%"HOLE"
"1","(-7150,2800)","0","pure_quanta","I31";
;
LOCATION"H34"
$SEC"1"
CDS_SEC"1"
MATERIAL"EMPTY"
PACK_TYPE"TH"
NEEDS_NO_SIZE"TRUE"
CDS_LIB"pure_quanta"
PART_NUMBER"HOLE1226";
"1 \B"
$PN"1"34;
%"UNIVERSAL_GND"
"1","(-7350,2725)","0","pure_quanta_power","I32";
;
CDS_LIB"pure_quanta_power"
HDL_POWER"GND";
"A"34;
%"HOLE"
"1","(-6575,2800)","0","pure_quanta","I33";
;
LOCATION"H38"
$SEC"1"
CDS_SEC"1"
MATERIAL"EMPTY"
PACK_TYPE"TH"
CDS_LIB"pure_quanta"
NEEDS_NO_SIZE"TRUE"
PART_NUMBER"HOLE1226";
"1 \B"
$PN"1"35;
%"UNIVERSAL_GND"
"1","(-6775,2725)","0","pure_quanta_power","I34";
;
CDS_LIB"pure_quanta_power"
HDL_POWER"GND";
"A"35;
%"UNIVERSAL_GND"
"1","(-7950,3325)","0","pure_quanta_power","I35";
;
CDS_LIB"pure_quanta_power"
HDL_POWER"GND";
"A"36;
%"HOLE"
"1","(-7750,3400)","0","pure_quanta","I36";
;
LOCATION"H33"
$SEC"1"
CDS_SEC"1"
MATERIAL"EMPTY"
PACK_TYPE"TH"
NEEDS_NO_SIZE"TRUE"
CDS_LIB"pure_quanta"
PART_NUMBER"HOLE1226";
"1 \B"
$PN"1"36;
%"UNIVERSAL_GND"
"1","(-7375,3325)","0","pure_quanta_power","I37";
;
CDS_LIB"pure_quanta_power"
HDL_POWER"GND";
"A"37;
%"HOLE"
"1","(-7175,3400)","0","pure_quanta","I38";
;
LOCATION"H37"
$SEC"1"
CDS_SEC"1"
MATERIAL"EMPTY"
PACK_TYPE"TH"
NEEDS_NO_SIZE"TRUE"
CDS_LIB"pure_quanta"
PART_NUMBER"HOLE1226";
"1 \B"
$PN"1"37;
%"UNIVERSAL_GND"
"1","(-6875,3325)","0","pure_quanta_power","I39";
;
CDS_LIB"pure_quanta_power"
HDL_POWER"GND";
"A"38;
%"HOLE"
"1","(-8875,2825)","0","pure_quanta","I4";
;
LOCATION"H53"
$SEC"1"
CDS_SEC"1"
MATERIAL"EMPTY"
PACK_TYPE"TH"
NEEDS_NO_SIZE"TRUE"
CDS_LIB"pure_quanta"
PART_NUMBER"HOLE1226";
"1 \B"
$PN"1"33;
%"HOLE"
"1","(-6675,3400)","0","pure_quanta","I40";
;
LOCATION"H43"
$SEC"1"
CDS_SEC"1"
MATERIAL"EMPTY"
PACK_TYPE"TH"
NEEDS_NO_SIZE"TRUE"
CDS_LIB"pure_quanta"
PART_NUMBER"HOLE1226";
"1 \B"
$PN"1"38;
%"HOLE"
"1","(-6225,4275)","0","pure_quanta","I41";
;
LOCATION"H27"
$SEC"1"
CDS_SEC"1"
MATERIAL"EMPTY"
PACK_TYPE"TH"
NEEDS_NO_SIZE"TRUE"
CDS_LIB"pure_quanta"
PART_NUMBER"DUMMY50";
"1 \B"
$PN"1"0;
%"UNIVERSAL_GND"
"1","(-5700,450)","0","pure_quanta_power","I42";
;
CDS_LIB"pure_quanta_power"
HDL_POWER"GND";
"A"52;
%"GND_HOLE"
"1","(-5425,850)","0","pure_quanta","I43";
;
LOCATION"H115"
$SEC"1"
CDS_SEC"1"
MATERIAL"EMPTY"
PACK_TYPE"TH"
NEEDS_NO_SIZE"TRUE"
CDS_LIB"pure_quanta"
PART_NUMBER"GND_HOLE514";
"GND5"
$PN"5"52;
"GND6"
$PN"6"52;
"GND2"
$PN"2"52;
"GND3"
$PN"3"52;
"GND7"
$PN"7"52;
"GND8"
$PN"8"52;
"GND9"
$PN"9"52;
"GND4"
$PN"4"52;
%"UNIVERSAL_GND"
"1","(-6275,2725)","0","pure_quanta_power","I44";
;
CDS_LIB"pure_quanta_power"
HDL_POWER"GND";
"A"39;
%"HOLE"
"1","(-6075,2800)","0","pure_quanta","I45";
;
LOCATION"H44"
$SEC"1"
CDS_SEC"1"
MATERIAL"EMPTY"
PACK_TYPE"TH"
NEEDS_NO_SIZE"TRUE"
CDS_LIB"pure_quanta"
PART_NUMBER"HOLE1226";
"1 \B"
$PN"1"39;
%"HOLE"
"1","(-6125,3400)","0","pure_quanta","I46";
;
LOCATION"H49"
$SEC"1"
CDS_SEC"1"
PACK_TYPE"TH"
MATERIAL"EMPTY"
NEEDS_NO_SIZE"TRUE"
CDS_LIB"pure_quanta"
PART_NUMBER"HOLE1226";
"1 \B"
$PN"1"40;
%"UNIVERSAL_GND"
"1","(-6325,3325)","0","pure_quanta_power","I47";
;
CDS_LIB"pure_quanta_power"
HDL_POWER"GND";
"A"40;
%"UNIVERSAL_GND"
"1","(-5800,3325)","0","pure_quanta_power","I48";
;
CDS_LIB"pure_quanta_power"
HDL_POWER"GND";
"A"41;
%"HOLE"
"1","(-5600,3400)","0","pure_quanta","I49";
;
LOCATION"H50"
$SEC"1"
CDS_SEC"1"
MATERIAL"EMPTY"
PACK_TYPE"TH"
NEEDS_NO_SIZE"TRUE"
CDS_LIB"pure_quanta"
PART_NUMBER"HOLE1226";
"1 \B"
$PN"1"41;
%"HOLE"
"1","(-8850,3400)","0","pure_quanta","I5";
;
LOCATION"H21"
$SEC"1"
CDS_SEC"1"
PACK_TYPE"TH"
MATERIAL"EMPTY"
CDS_LIB"pure_quanta"
NEEDS_NO_SIZE"TRUE"
PART_NUMBER"HOLE1226";
"1 \B"
$PN"1"44;
%"HOLE"
"1","(-5725,4275)","0","pure_quanta","I50";
;
LOCATION"H28"
$SEC"1"
CDS_SEC"1"
MATERIAL"EMPTY"
PACK_TYPE"TH"
NEEDS_NO_SIZE"TRUE"
CDS_LIB"pure_quanta"
PART_NUMBER"DUMMY50";
"1 \B"
$PN"1"0;
%"HOLE"
"1","(-5200,4275)","0","pure_quanta","I51";
;
LOCATION"H29"
$SEC"1"
CDS_SEC"1"
MATERIAL"EMPTY"
PACK_TYPE"TH"
CDS_LIB"pure_quanta"
NEEDS_NO_SIZE"TRUE"
PART_NUMBER"DUMMY50";
"1 \B"
$PN"1"0;
%"HOLE"
"1","(-5025,3400)","0","pure_quanta","I52";
;
LOCATION"H54"
$SEC"1"
CDS_SEC"1"
MATERIAL"EMPTY"
PACK_TYPE"TH"
CDS_LIB"pure_quanta"
NEEDS_NO_SIZE"TRUE"
PART_NUMBER"HOLE1226";
"1 \B"
$PN"1"42;
%"UNIVERSAL_GND"
"1","(-5225,3325)","0","pure_quanta_power","I53";
;
CDS_LIB"pure_quanta_power"
HDL_POWER"GND";
"A"42;
%"UNIVERSAL_GND"
"1","(-5775,2700)","0","pure_quanta_power","I54";
;
CDS_LIB"pure_quanta_power"
HDL_POWER"GND";
"A"43;
%"HOLE"
"1","(-5575,2775)","0","pure_quanta","I55";
;
LOCATION"H13"
$SEC"1"
CDS_SEC"1"
MATERIAL"EMPTY"
PACK_TYPE"TH"
CDS_LIB"pure_quanta"
NEEDS_NO_SIZE"TRUE"
PART_NUMBER"HOLE1226";
"1 \B"
$PN"1"43;
%"HOLE"
"1","(-4700,4275)","0","pure_quanta","I56";
;
LOCATION"H30"
$SEC"1"
CDS_SEC"1"
MATERIAL"EMPTY"
PACK_TYPE"TH"
CDS_LIB"pure_quanta"
NEEDS_NO_SIZE"TRUE"
PART_NUMBER"DUMMY50";
"1 \B"
$PN"1"0;
%"UNIVERSAL_GND"
"1","(-9050,3325)","0","pure_quanta_power","I6";
;
CDS_LIB"pure_quanta_power"
HDL_POWER"GND";
"A"44;
%"HOLE"
"1","(-8300,3400)","0","pure_quanta","I7";
;
LOCATION"H8027"
$SEC"1"
CDS_SEC"1"
PACK_TYPE"TH"
MATERIAL"EMPTY"
NEEDS_NO_SIZE"TRUE"
CDS_LIB"pure_quanta"
PART_NUMBER"HOLE1226";
"1 \B"
$PN"1"45;
%"UNIVERSAL_GND"
"1","(-8500,3325)","0","pure_quanta_power","I8";
;
CDS_LIB"pure_quanta_power"
HDL_POWER"GND";
"A"45;
%"HOLE"
"1","(-3675,500)","0","pure_quanta","I84";
;
LOCATION"H124"
$SEC"1"
CDS_SEC"1"
MATERIAL"EMPTY"
PACK_TYPE"TH"
CDS_LIB"pure_quanta"
NEEDS_NO_SIZE"TRUE"
PART_NUMBER"TMP-C_T2I_ALEX_1121_1";
"1 \B"
$PN"1"0;
%"HOLE"
"1","(-3625,925)","0","pure_quanta","I85";
;
LOCATION"H125"
$SEC"1"
CDS_SEC"1"
PACK_TYPE"TH"
MATERIAL"EMPTY"
NEEDS_NO_SIZE"TRUE"
CDS_LIB"pure_quanta"
PART_NUMBER"TMP-C_T2I_ALEX_1121_1";
"1 \B"
$PN"1"0;
%"UNIVERSAL_GND"
"1","(-5250,2700)","0","pure_quanta_power","I86";
;
CDS_LIB"pure_quanta_power"
HDL_POWER"GND";
"A"46;
%"HOLE"
"1","(-5050,2775)","0","pure_quanta","I87";
;
LOCATION"H11"
$SEC"1"
CDS_SEC"1"
MATERIAL"EMPTY"
PACK_TYPE"TH"
CDS_LIB"pure_quanta"
NEEDS_NO_SIZE"TRUE"
PART_NUMBER"HOLE1226";
"1 \B"
$PN"1"46;
%"HOLE"
"1","(-4000,4325)","0","pure_quanta","I88";
;
LOCATION"H74"
$SEC"1"
CDS_SEC"1"
MATERIAL"EMPTY"
PACK_TYPE"TH"
CDS_LIB"pure_quanta"
NEEDS_NO_SIZE"TRUE"
PART_NUMBER"HOLE1247";
"1 \B"
$PN"1"0;
%"HOLE"
"1","(-3500,4325)","0","pure_quanta","I89";
;
LOCATION"H75"
$SEC"1"
CDS_SEC"1"
MATERIAL"EMPTY"
PACK_TYPE"TH"
CDS_LIB"pure_quanta"
NEEDS_NO_SIZE"TRUE"
PART_NUMBER"HOLE1247";
"1 \B"
$PN"1"0;
%"UNIVERSAL_GND"
"1","(-9000,4075)","0","pure_quanta_power","I9";
;
CDS_LIB"pure_quanta_power"
HDL_POWER"GND";
"A"53;
%"UNIVERSAL_GND"
"1","(-4225,3125)","0","pure_quanta_power","I90";
;
CDS_LIB"pure_quanta_power"
HDL_POWER"GND";
"A"54;
%"HOLE"
"1","(-3950,3275)","0","pure_quanta","I91";
;
LOCATION"H31"
$SEC"1"
CDS_SEC"1"
PACK_TYPE"TH"
MATERIAL"EMPTY"
NEEDS_NO_SIZE"TRUE"
CDS_LIB"pure_quanta"
PART_NUMBER"HOLE1248";
"1 \B"
$PN"1"54;
%"UNIVERSAL_GND"
"1","(-3725,3125)","0","pure_quanta_power","I92";
;
CDS_LIB"pure_quanta_power"
HDL_POWER"GND";
"A"55;
%"HOLE"
"1","(-3450,3275)","0","pure_quanta","I93";
;
LOCATION"H32"
$SEC"1"
CDS_SEC"1"
PACK_TYPE"TH"
MATERIAL"EMPTY"
NEEDS_NO_SIZE"TRUE"
CDS_LIB"pure_quanta"
PART_NUMBER"HOLE1248";
"1 \B"
$PN"1"55;
%"HOLE"
"1","(-2850,900)","0","pure_quanta","I94";
;
LOCATION"H127"
$SEC"1"
CDS_SEC"1"
PACK_TYPE"TH"
MATERIAL"EMPTY"
NEEDS_NO_SIZE"TRUE"
CDS_LIB"pure_quanta"
PART_NUMBER"TMP-C_T2I_ALEX_1121_1";
"1 \B"
$PN"1"0;
END.
